(kicad_pcb
	(version 20260206)
	(generator "pcbnew")
	(generator_version "10.0")
	(general
		(thickness 1.6)
		(legacy_teardrops no)
	)
	(paper "A4")
	(title_block
		(title "Bryce Canyon_IOM_M2_16342-2_OCP.brd")
		(comment 1 "Bryce Canyon / footprints 1131-1138 of 1146")
	)
	(layers
		(0 "F.Cu" signal "TOP")
		(4 "In1.Cu" signal "L2GND")
		(6 "In2.Cu" signal "L3")
		(8 "In3.Cu" signal "L4VCC")
		(10 "In4.Cu" signal "L5VCC")
		(12 "In5.Cu" signal "L6")
		(14 "In6.Cu" signal "L7GND")
		(2 "B.Cu" signal "BOTTOM")
		(9 "F.Adhes" user "F.Adhesive")
		(11 "B.Adhes" user "B.Adhesive")
		(13 "F.Paste" user "Package Geometry/Pastemask Top")
		(15 "B.Paste" user "Package Geometry/Pastemask Bottom")
		(5 "F.SilkS" user "Ref Des/Silkscreen Top")
		(7 "B.SilkS" user "Ref Des/Silkscreen Bottom")
		(1 "F.Mask" user "Board Geometry/Soldermask Top")
		(3 "B.Mask" user "Board Geometry/Soldermask Bottom")
		(17 "Dwgs.User" user "User.Drawings")
		(19 "Cmts.User" user "User.Comments")
		(21 "Eco1.User" user "User.Eco1")
		(23 "Eco2.User" user "User.Eco2")
		(25 "Edge.Cuts" user "Board Geometry/Outline")
		(27 "Margin" user)
		(31 "F.CrtYd" user "Package Geometry/Place Bound Top")
		(29 "B.CrtYd" user "Package Geometry/Place Bound Bottom")
		(35 "F.Fab" user "Ref Des/Assembly Top")
		(33 "B.Fab" user "Ref Des/Assembly Bottom")
	)
	(footprint ""
		(layer "B.Cu")
		(at 52.5526 -146.5834 -90)
		(property "Reference" "TP51"
			(at 0 0 90)
			(layer "B.SilkS")
			(hide yes)
			(effects
				(font
					(size 1.27 1.27)
				)
				(justify mirror)
			)
		)
		(property "Value" "TPAD28-2-GP"
			(at 0.0127 -1.6637 270)
			(unlocked yes)
			(layer "B.Fab")
			(hide yes)
			(effects
				(font
					(size 1.016 1.016)
					(thickness 0.1524)
				)
				(justify mirror)
			)
		)
		(property "Device Type" "TPAD28"
			(at 0.0127 -3.1877 270)
			(unlocked yes)
			(layer "B.Fab")
			(hide yes)
			(effects
				(font
					(size 1.016 1.016)
					(thickness 0.1524)
				)
				(justify mirror)
			)
		)
		(duplicate_pad_numbers_are_jumpers no)
		(fp_poly
			(pts
				(arc
					(start 0 -0.3556)
					(mid 0 0.3556)
					(end 0 -0.3556)
				)
			)
			(stroke
				(width 0)
				(type default)
			)
			(fill no)
			(layer "B.CrtYd")
		)
		(fp_poly
			(pts
				(arc
					(start 0 -0.6096)
					(mid 0 0.6096)
					(end 0 -0.6096)
				)
			)
			(stroke
				(width 0)
				(type default)
			)
			(fill no)
			(layer "B.Fab")
		)
		(pad "1" smd circle
			(at 0 0 90)
			(size 0.7112 0.7112)
			(layers "B.Cu" "B.Mask" "B.Paste")
			(net "RMII_BMC_MDC_R")
		)
	)
	(footprint ""
		(layer "B.Cu")
		(at 53.88991 -123.115832)
		(property "Reference" "R347"
			(at 0 0 0)
			(layer "B.SilkS")
			(hide yes)
			(effects
				(font
					(size 1.27 1.27)
				)
				(justify mirror)
			)
		)
		(property "Value" "4K7R2F-GP"
			(at -0.064008 -3.993896 0)
			(unlocked yes)
			(layer "B.Fab")
			(hide yes)
			(effects
				(font
					(size 1.016 1.016)
					(thickness 0.1524)
				)
				(justify mirror)
			)
		)
		(property "Device Type" "R402H16"
			(at -0.064008 -5.517896 0)
			(unlocked yes)
			(layer "B.Fab")
			(hide yes)
			(effects
				(font
					(size 1.016 1.016)
					(thickness 0.1524)
				)
				(justify mirror)
			)
		)
		(duplicate_pad_numbers_are_jumpers no)
		(fp_line
			(start -0.508 -0.9398)
			(end 0.508 -0.9398)
			(stroke
				(width 0.1524)
				(type default)
			)
			(layer "B.SilkS")
		)
		(fp_line
			(start 0.508 -0.9398)
			(end 0.508 0.9398)
			(stroke
				(width 0.1524)
				(type default)
			)
			(layer "B.SilkS")
		)
		(fp_rect
			(start 0.508 0.9398)
			(end -0.508 -0.9398)
			(stroke
				(width 0)
				(type default)
			)
			(fill no)
			(layer "B.CrtYd")
		)
		(fp_rect
			(start 0.508 0.9398)
			(end -0.508 -0.9398)
			(stroke
				(width 0)
				(type default)
			)
			(fill no)
			(layer "B.Fab")
		)
		(pad "1" smd custom
			(at 0 -0.4445 180)
			(size 0.1397 0.1397)
			(layers "B.Cu" "B.Mask" "B.Paste")
			(net "P3V3_STBY")
			(options
				(clearance outline)
				(anchor circle)
			)
			(primitives
				(gr_poly
					(pts
						(arc
							(start -0.1778 0.2794)
							(mid -0.249642 0.249642)
							(end -0.2794 0.1778)
						)
						(arc
							(start -0.2794 -0.1778)
							(mid -0.249642 -0.249642)
							(end -0.1778 -0.2794)
						)
						(arc
							(start 0.1778 -0.2794)
							(mid 0.249642 -0.249642)
							(end 0.2794 -0.1778)
						)
						(arc
							(start 0.2794 0.1778)
							(mid 0.249642 0.249642)
							(end 0.1778 0.2794)
						)
					)
					(width 0)
					(fill yes)
				)
			)
		)
		(pad "2" smd custom
			(at 0 0.4445 180)
			(size 0.1397 0.1397)
			(layers "B.Cu" "B.Mask" "B.Paste")
			(net "TEMP_3_A2")
			(options
				(clearance outline)
				(anchor circle)
			)
			(primitives
				(gr_poly
					(pts
						(arc
							(start -0.1778 0.2794)
							(mid -0.249642 0.249642)
							(end -0.2794 0.1778)
						)
						(arc
							(start -0.2794 -0.1778)
							(mid -0.249642 -0.249642)
							(end -0.1778 -0.2794)
						)
						(arc
							(start 0.1778 -0.2794)
							(mid 0.249642 -0.249642)
							(end 0.2794 -0.1778)
						)
						(arc
							(start 0.2794 0.1778)
							(mid 0.249642 0.249642)
							(end 0.1778 0.2794)
						)
					)
					(width 0)
					(fill yes)
				)
			)
		)
	)
	(footprint ""
		(layer "B.Cu")
		(at 35.2298 -121.8438 90)
		(property "Reference" "R780"
			(at 0 0 90)
			(layer "B.SilkS")
			(hide yes)
			(effects
				(font
					(size 1.27 1.27)
				)
				(justify mirror)
			)
		)
		(property "Value" "0R2J-2-GP"
			(at -0.064008 -3.993896 90)
			(unlocked yes)
			(layer "B.Fab")
			(hide yes)
			(effects
				(font
					(size 1.016 1.016)
					(thickness 0.1524)
				)
				(justify mirror)
			)
		)
		(property "Device Type" "R402H16"
			(at -0.064008 -5.517896 90)
			(unlocked yes)
			(layer "B.Fab")
			(hide yes)
			(effects
				(font
					(size 1.016 1.016)
					(thickness 0.1524)
				)
				(justify mirror)
			)
		)
		(duplicate_pad_numbers_are_jumpers no)
		(fp_line
			(start 0.508 -0.9398)
			(end 0.508 0.9398)
			(stroke
				(width 0.1524)
				(type default)
			)
			(layer "B.SilkS")
		)
		(fp_line
			(start -0.508 -0.9398)
			(end 0.508 -0.9398)
			(stroke
				(width 0.1524)
				(type default)
			)
			(layer "B.SilkS")
		)
		(fp_rect
			(start 0.508 0.9398)
			(end -0.508 -0.9398)
			(stroke
				(width 0)
				(type default)
			)
			(fill no)
			(layer "B.CrtYd")
		)
		(fp_rect
			(start 0.508 0.9398)
			(end -0.508 -0.9398)
			(stroke
				(width 0)
				(type default)
			)
			(fill no)
			(layer "B.Fab")
		)
		(pad "1" smd custom
			(at 0 -0.4445 270)
			(size 0.1397 0.1397)
			(layers "B.Cu" "B.Mask" "B.Paste")
			(net "FLA_CS_0_R")
			(options
				(clearance outline)
				(anchor circle)
			)
			(primitives
				(gr_poly
					(pts
						(arc
							(start -0.1778 0.2794)
							(mid -0.249642 0.249642)
							(end -0.2794 0.1778)
						)
						(arc
							(start -0.2794 -0.1778)
							(mid -0.249642 -0.249642)
							(end -0.1778 -0.2794)
						)
						(arc
							(start 0.1778 -0.2794)
							(mid 0.249642 -0.249642)
							(end 0.2794 -0.1778)
						)
						(arc
							(start 0.2794 0.1778)
							(mid 0.249642 0.249642)
							(end 0.1778 0.2794)
						)
					)
					(width 0)
					(fill yes)
				)
			)
		)
		(pad "2" smd custom
			(at 0 0.4445 270)
			(size 0.1397 0.1397)
			(layers "B.Cu" "B.Mask" "B.Paste")
			(net "BMC_CPU_EN")
			(options
				(clearance outline)
				(anchor circle)
			)
			(primitives
				(gr_poly
					(pts
						(arc
							(start -0.1778 0.2794)
							(mid -0.249642 0.249642)
							(end -0.2794 0.1778)
						)
						(arc
							(start -0.2794 -0.1778)
							(mid -0.249642 -0.249642)
							(end -0.1778 -0.2794)
						)
						(arc
							(start 0.1778 -0.2794)
							(mid 0.249642 -0.249642)
							(end 0.2794 -0.1778)
						)
						(arc
							(start 0.2794 0.1778)
							(mid 0.249642 0.249642)
							(end 0.1778 0.2794)
						)
					)
					(width 0)
					(fill yes)
				)
			)
		)
	)
	(footprint ""
		(layer "B.Cu")
		(at 63.3222 -136.1948 -90)
		(property "Reference" "R729"
			(at 0 0 90)
			(layer "B.SilkS")
			(hide yes)
			(effects
				(font
					(size 1.27 1.27)
				)
				(justify mirror)
			)
		)
		(property "Value" "10KR2F-2-GP"
			(at -0.064008 -3.993896 270)
			(unlocked yes)
			(layer "B.Fab")
			(hide yes)
			(effects
				(font
					(size 1.016 1.016)
					(thickness 0.1524)
				)
				(justify mirror)
			)
		)
		(property "Device Type" "R402H16"
			(at -0.064008 -5.517896 270)
			(unlocked yes)
			(layer "B.Fab")
			(hide yes)
			(effects
				(font
					(size 1.016 1.016)
					(thickness 0.1524)
				)
				(justify mirror)
			)
		)
		(duplicate_pad_numbers_are_jumpers no)
		(fp_line
			(start -0.508 -0.9398)
			(end 0.508 -0.9398)
			(stroke
				(width 0.1524)
				(type default)
			)
			(layer "B.SilkS")
		)
		(fp_line
			(start 0.508 -0.9398)
			(end 0.508 0.9398)
			(stroke
				(width 0.1524)
				(type default)
			)
			(layer "B.SilkS")
		)
		(fp_rect
			(start 0.508 0.9398)
			(end -0.508 -0.9398)
			(stroke
				(width 0)
				(type default)
			)
			(fill no)
			(layer "B.CrtYd")
		)
		(fp_rect
			(start 0.508 0.9398)
			(end -0.508 -0.9398)
			(stroke
				(width 0)
				(type default)
			)
			(fill no)
			(layer "B.Fab")
		)
		(pad "1" smd custom
			(at 0 -0.4445 90)
			(size 0.1397 0.1397)
			(layers "B.Cu" "B.Mask" "B.Paste")
			(net "TP_BMC_GPIOA0")
			(options
				(clearance outline)
				(anchor circle)
			)
			(primitives
				(gr_poly
					(pts
						(arc
							(start -0.1778 0.2794)
							(mid -0.249642 0.249642)
							(end -0.2794 0.1778)
						)
						(arc
							(start -0.2794 -0.1778)
							(mid -0.249642 -0.249642)
							(end -0.1778 -0.2794)
						)
						(arc
							(start 0.1778 -0.2794)
							(mid 0.249642 -0.249642)
							(end 0.2794 -0.1778)
						)
						(arc
							(start 0.2794 0.1778)
							(mid 0.249642 0.249642)
							(end 0.1778 0.2794)
						)
					)
					(width 0)
					(fill yes)
				)
			)
		)
		(pad "2" smd custom
			(at 0 0.4445 90)
			(size 0.1397 0.1397)
			(layers "B.Cu" "B.Mask" "B.Paste")
			(net "GND")
			(options
				(clearance outline)
				(anchor circle)
			)
			(primitives
				(gr_poly
					(pts
						(arc
							(start -0.1778 0.2794)
							(mid -0.249642 0.249642)
							(end -0.2794 0.1778)
						)
						(arc
							(start -0.2794 -0.1778)
							(mid -0.249642 -0.249642)
							(end -0.1778 -0.2794)
						)
						(arc
							(start 0.1778 -0.2794)
							(mid 0.249642 -0.249642)
							(end 0.2794 -0.1778)
						)
						(arc
							(start 0.2794 0.1778)
							(mid 0.249642 0.249642)
							(end 0.1778 0.2794)
						)
					)
					(width 0)
					(fill yes)
				)
			)
		)
	)
	(footprint ""
		(layer "B.Cu")
		(at 55.800752 -149.122384)
		(property "Reference" "TP80"
			(at 0 0 0)
			(layer "B.SilkS")
			(hide yes)
			(effects
				(font
					(size 1.27 1.27)
				)
				(justify mirror)
			)
		)
		(property "Value" "TPAD28-2-GP"
			(at 0.0127 -1.6637 0)
			(unlocked yes)
			(layer "B.Fab")
			(hide yes)
			(effects
				(font
					(size 1.016 1.016)
					(thickness 0.1524)
				)
				(justify mirror)
			)
		)
		(property "Device Type" "TPAD28"
			(at 0.0127 -3.1877 0)
			(unlocked yes)
			(layer "B.Fab")
			(hide yes)
			(effects
				(font
					(size 1.016 1.016)
					(thickness 0.1524)
				)
				(justify mirror)
			)
		)
		(duplicate_pad_numbers_are_jumpers no)
		(fp_poly
			(pts
				(arc
					(start 0.3556 0)
					(mid -0.3556 0)
					(end 0.3556 0)
				)
			)
			(stroke
				(width 0)
				(type default)
			)
			(fill no)
			(layer "B.CrtYd")
		)
		(fp_poly
			(pts
				(arc
					(start 0.6096 0)
					(mid -0.6096 0)
					(end 0.6096 0)
				)
			)
			(stroke
				(width 0)
				(type default)
			)
			(fill no)
			(layer "B.Fab")
		)
		(pad "1" smd circle
			(at 0 0 180)
			(size 0.7112 0.7112)
			(layers "B.Cu" "B.Mask" "B.Paste")
			(net "JTAG_BMC_TMS")
		)
	)
	(footprint ""
		(layer "B.Cu")
		(at 54.229 -162.1536 90)
		(property "Reference" "C117"
			(at 0 0 90)
			(layer "B.SilkS")
			(hide yes)
			(effects
				(font
					(size 1.27 1.27)
				)
				(justify mirror)
			)
		)
		(property "Value" "SCD1U25V2KX-2-GP"
			(at -1.1811 -2.7051 90)
			(unlocked yes)
			(layer "B.Fab")
			(hide yes)
			(effects
				(font
					(size 1.016 1.016)
					(thickness 0.1524)
				)
				(justify mirror)
			)
		)
		(property "Device Type" "C402H22"
			(at -1.1811 -4.2291 90)
			(unlocked yes)
			(layer "B.Fab")
			(hide yes)
			(effects
				(font
					(size 1.016 1.016)
					(thickness 0.1524)
				)
				(justify mirror)
			)
		)
		(duplicate_pad_numbers_are_jumpers no)
		(fp_rect
			(start 0.4318 0.9525)
			(end -0.4318 -0.9525)
			(stroke
				(width 0)
				(type default)
			)
			(fill no)
			(layer "B.CrtYd")
		)
		(fp_rect
			(start 0.4318 0.9525)
			(end -0.4318 -0.9525)
			(stroke
				(width 0)
				(type default)
			)
			(fill no)
			(layer "B.Fab")
		)
		(pad "1" smd custom
			(at 0 -0.4445 270)
			(size 0.1524 0.1524)
			(layers "B.Cu" "B.Mask" "B.Paste")
			(net "ADC_12V")
			(options
				(clearance outline)
				(anchor circle)
			)
			(primitives
				(gr_poly
					(pts
						(arc
							(start 0.3048 0.2032)
							(mid 0.275042 0.275042)
							(end 0.2032 0.3048)
						)
						(arc
							(start -0.2032 0.3048)
							(mid -0.275042 0.275042)
							(end -0.3048 0.2032)
						)
						(arc
							(start -0.3048 -0.2032)
							(mid -0.275042 -0.275042)
							(end -0.2032 -0.3048)
						)
						(arc
							(start 0.2032 -0.3048)
							(mid 0.275042 -0.275042)
							(end 0.3048 -0.2032)
						)
					)
					(width 0)
					(fill yes)
				)
			)
		)
		(pad "2" smd custom
			(at 0 0.4445 270)
			(size 0.1524 0.1524)
			(layers "B.Cu" "B.Mask" "B.Paste")
			(net "GND")
			(options
				(clearance outline)
				(anchor circle)
			)
			(primitives
				(gr_poly
					(pts
						(arc
							(start 0.3048 0.2032)
							(mid 0.275042 0.275042)
							(end 0.2032 0.3048)
						)
						(arc
							(start -0.2032 0.3048)
							(mid -0.275042 0.275042)
							(end -0.3048 0.2032)
						)
						(arc
							(start -0.3048 -0.2032)
							(mid -0.275042 -0.275042)
							(end -0.2032 -0.3048)
						)
						(arc
							(start 0.2032 -0.3048)
							(mid 0.275042 -0.275042)
							(end 0.3048 -0.2032)
						)
					)
					(width 0)
					(fill yes)
				)
			)
		)
	)
	(footprint ""
		(layer "B.Cu")
		(at 19.874738 -143.326866 180)
		(property "Reference" "C66"
			(at 0 0 0)
			(layer "B.SilkS")
			(hide yes)
			(effects
				(font
					(size 1.27 1.27)
				)
				(justify mirror)
			)
		)
		(property "Value" "SCD1U16V2KX-3GP"
			(at -1.1811 -2.7051 180)
			(unlocked yes)
			(layer "B.Fab")
			(hide yes)
			(effects
				(font
					(size 1.016 1.016)
					(thickness 0.1524)
				)
				(justify mirror)
			)
		)
		(property "Device Type" "C402H22"
			(at -1.1811 -4.2291 180)
			(unlocked yes)
			(layer "B.Fab")
			(hide yes)
			(effects
				(font
					(size 1.016 1.016)
					(thickness 0.1524)
				)
				(justify mirror)
			)
		)
		(duplicate_pad_numbers_are_jumpers no)
		(fp_rect
			(start 0.4318 0.9525)
			(end -0.4318 -0.9525)
			(stroke
				(width 0)
				(type default)
			)
			(fill no)
			(layer "B.CrtYd")
		)
		(fp_rect
			(start 0.4318 0.9525)
			(end -0.4318 -0.9525)
			(stroke
				(width 0)
				(type default)
			)
			(fill no)
			(layer "B.Fab")
		)
		(pad "1" smd custom
			(at 0 -0.4445)
			(size 0.1524 0.1524)
			(layers "B.Cu" "B.Mask" "B.Paste")
			(net "MEMCK_TER")
			(options
				(clearance outline)
				(anchor circle)
			)
			(primitives
				(gr_poly
					(pts
						(arc
							(start 0.3048 0.2032)
							(mid 0.275042 0.275042)
							(end 0.2032 0.3048)
						)
						(arc
							(start -0.2032 0.3048)
							(mid -0.275042 0.275042)
							(end -0.3048 0.2032)
						)
						(arc
							(start -0.3048 -0.2032)
							(mid -0.275042 -0.275042)
							(end -0.2032 -0.3048)
						)
						(arc
							(start 0.2032 -0.3048)
							(mid 0.275042 -0.275042)
							(end 0.3048 -0.2032)
						)
					)
					(width 0)
					(fill yes)
				)
			)
		)
		(pad "2" smd custom
			(at 0 0.4445)
			(size 0.1524 0.1524)
			(layers "B.Cu" "B.Mask" "B.Paste")
			(net "GND")
			(options
				(clearance outline)
				(anchor circle)
			)
			(primitives
				(gr_poly
					(pts
						(arc
							(start 0.3048 0.2032)
							(mid 0.275042 0.275042)
							(end 0.2032 0.3048)
						)
						(arc
							(start -0.2032 0.3048)
							(mid -0.275042 0.275042)
							(end -0.3048 0.2032)
						)
						(arc
							(start -0.3048 -0.2032)
							(mid -0.275042 -0.275042)
							(end -0.2032 -0.3048)
						)
						(arc
							(start 0.2032 -0.3048)
							(mid 0.275042 -0.275042)
							(end 0.3048 -0.2032)
						)
					)
					(width 0)
					(fill yes)
				)
			)
		)
	)
	(footprint ""
		(layer "B.Cu")
		(at 62.2554 -160.782 180)
		(property "Reference" "C87"
			(at 0 0 0)
			(layer "B.SilkS")
			(hide yes)
			(effects
				(font
					(size 1.27 1.27)
				)
				(justify mirror)
			)
		)
		(property "Value" "SC1U16V3KX-5GP"
			(at 0 -2.8194 180)
			(unlocked yes)
			(layer "B.Fab")
			(hide yes)
			(effects
				(font
					(size 1.016 1.016)
					(thickness 0.1524)
				)
				(justify mirror)
			)
		)
		(property "Device Type" "C603H36"
			(at 0 -4.3434 180)
			(unlocked yes)
			(layer "B.Fab")
			(hide yes)
			(effects
				(font
					(size 1.016 1.016)
					(thickness 0.1524)
				)
				(justify mirror)
			)
		)
		(duplicate_pad_numbers_are_jumpers no)
		(fp_line
			(start -0.508 0)
			(end 0.508 0)
			(stroke
				(width 0.2032)
				(type default)
			)
			(layer "B.SilkS")
		)
		(fp_rect
			(start 0.5842 1.3335)
			(end -0.5842 -1.3335)
			(stroke
				(width 0)
				(type default)
			)
			(fill no)
			(layer "B.CrtYd")
		)
		(fp_rect
			(start 0.5842 1.3335)
			(end -0.5842 -1.3335)
			(stroke
				(width 0)
				(type default)
			)
			(fill no)
			(layer "B.Fab")
		)
		(pad "1" smd custom
			(at 0 -0.762)
			(size 0.2159 0.2159)
			(layers "B.Cu" "B.Mask" "B.Paste")
			(net "ADCAV33")
			(options
				(clearance outline)
				(anchor circle)
			)
			(primitives
				(gr_poly
					(pts
						(arc
							(start -0.3302 0.4318)
							(mid -0.402042 0.402042)
							(end -0.4318 0.3302)
						)
						(arc
							(start -0.4318 -0.3302)
							(mid -0.402042 -0.402042)
							(end -0.3302 -0.4318)
						)
						(arc
							(start 0.3302 -0.4318)
							(mid 0.402042 -0.402042)
							(end 0.4318 -0.3302)
						)
						(arc
							(start 0.4318 0.3302)
							(mid 0.402042 0.402042)
							(end 0.3302 0.4318)
						)
					)
					(width 0)
					(fill yes)
				)
			)
		)
		(pad "2" smd custom
			(at 0 0.762)
			(size 0.2159 0.2159)
			(layers "B.Cu" "B.Mask" "B.Paste")
			(net "GND")
			(options
				(clearance outline)
				(anchor circle)
			)
			(primitives
				(gr_poly
					(pts
						(arc
							(start -0.3302 0.4318)
							(mid -0.402042 0.402042)
							(end -0.4318 0.3302)
						)
						(arc
							(start -0.4318 -0.3302)
							(mid -0.402042 -0.402042)
							(end -0.3302 -0.4318)
						)
						(arc
							(start 0.3302 -0.4318)
							(mid 0.402042 -0.402042)
							(end 0.4318 -0.3302)
						)
						(arc
							(start 0.4318 0.3302)
							(mid 0.402042 0.402042)
							(end 0.3302 0.4318)
						)
					)
					(width 0)
					(fill yes)
				)
			)
		)
	)
)
